FILE_TYPE = CONNECTIVITY;
{Allegro Design Entry HDL 16.6-p007 (v16-6-112F) 10/10/2012}
"PAGE_NUMBER" = 240;
0"NC";
1"GND\g";
2"P5V_STBY\g";
3"GND\g";
4"GND\g";
5"P3V3_STBY\g";
6"P12V_STBY\g";
7"GND\g";
8"GND\g";
9"GND\g";
10"GND\g";
11"GND\g";
12"GND\g";
13"GND\g";
14"GND\g";
15"AGND_P3V3_STBY\g";
16"AGND_P3V3_STBY\g";
17"AGND_P3V3_STBY\g";
18"AGND_P3V3_STBY\g";
19"AGND_P3V3_STBY\g";
20"AGND_P3V3_STBY\g";
21"GND\g";
22"P3V3_STBY\g";
23"P3V3_STBY\g";
24"VR_FET_SW_P12V_STBY_P3V3_STBY";
25"VR_P3V3_STBY_PHASE";
26"VR_P3V3_STBY_SNUB";
27"VR_P3V3_STBY_LGATE";
28"VR_P3V3_STBY_UGATE";
29"VSENSE_VOUT_P3V3_STBY";
30"VSENSE_RGND_P3V3_STBY";
31"VSENSE_P3V3_STBY";
32"VR_P3V3_STBY_BOOT_R";
33"VR_P3V3_STBY_BOOT";
34"PWRGD_P3V3_STBY";
35"PWRGD_P3V3_STBY_R";
36"VR_P3V3_STBY_EN";
37"VR_P3V3_STBY_OCSELECT";
38"PWRGD_P5V_STBY";
39"GND\g";
40"GND\g";
41"GND\g";
%"RES"
"2","(6425,1850)","2","mstr_discrete","I106";
;
CDS_SEC"1"
SEC_TYPE"0402"
SEC"1"
CDS_LIB"mstr_discrete"
BOM_COST"P3V3_STBY_VR"
ROOM"P3V3_STBY_VR"
CDS_LOCATION"R8F9"
LOCATION"R8F9"
VALUE"64.9K"
TOLERANCE"1%"
PACK_TYPE"0402"
MATERIAL"CHIP"
WATTAGE"1/16W"
PART_NUMBER"G21796-148";
"A"
$PN"1"37;
"B"
$PN"2"16;
%"CAP"
"1","(5600,3300)","2","mstr_discrete","I109";
;
CDS_SEC"1"
ROOM"P3V3_STBY_VR"
CDS_LOCATION"C2R11"
SEC"1"
BOM_COST"P3V3_STBY_VR"
SEC_TYPE"0603"
REUSE_ID"20"
CDS_LIB"mstr_discrete"
LOCATION"C2R11"
VALUE"4.7UF"
TOLERANCE"10%"
PACK_TYPE"0603"
VOLTAGE"6.3V"
MATERIAL"X6S"
PART_NUMBER"E15431-003";
"A"
$PN"1"2;
"B"
$PN"2"18;
%"GND"
"1","(5625,2150)","0","mstr_symbols","I110";
;
SIZE"1B"
HDL_POWER"GND"
VOLTAGE"0"
CDS_LIB"mstr_symbols"
BODY_TYPE"PLUMBING"
BOM"SYSB_CPLD"
BOM_COST"PVPP_KLM_VR"
ROOM"PVPP_KLM_VR";
"A\NAC"1;
%"RES"
"2","(5625,2400)","0","mstr_discrete","I111";
;
BOM_COST"P3V3_STBY_VR"
BOM"SYSB_CPLD"
CDS_SEC"1"
$SEC"1"
ROOM"P3V3_STBY_VR"
CDS_LOCATION"R8F1"
CDS_LIB"mstr_discrete"
PART_NUMBER"G21796-016"
MATERIAL"EMPTY"
LOCATION"R8F1"
VALUE"10.0K"
WATTAGE"1/16W"
TOLERANCE"1%"
PACK_TYPE"0402";
"A"
$PN"1"38;
"B"
$PN"2"1;
%"CAP"
"1","(6175,2475)","2","mstr_discrete","I113";
;
BOM_COST"P3V3_STBY_VR"
CDS_LIB"mstr_discrete"
ROOM"P3V3_STBY_VR"
FIN"VR_1P2"
REUSE_ID"1"
CDS_SEC"1"
$SEC"1"
CDS_LOCATION"C8E17"
PART_NUMBER"A36096-046"
LOCATION"C8E17"
VOLTAGE"50V"
TOLERANCE"10%"
MATERIAL"EMPTY"
VALUE"1000PF"
PACK_TYPE"0402LF";
"A"
$PN"1"38;
"B"
$PN"2"17;
%"P5V_STBY"
"1","(5725,3600)","0","mstr_symbols","I114";
;
SIZE"1B"
CDS_LIB"mstr_symbols"
VOLTAGE"+5.0V"
BODY_TYPE"PLUMBING"
HDL_POWER"P5V_STBY";
"G\NAC"2;
%"GND"
"1","(6350,3100)","0","mstr_symbols","I115";
;
SIZE"1B"
HDL_POWER"GND"
VOLTAGE"0"
CDS_LIB"mstr_symbols"
BODY_TYPE"PLUMBING"
ROOM"PVPP_KLM_VR"
BOM_COST"PVPP_KLM_VR";
"A\NAC"3;
%"CAP"
"1","(6350,3350)","0","mstr_discrete","I116";
;
REUSE_ID"17"
CDS_SEC"1"
CDS_LOCATION"C8F2"
$SEC"1"
ROOM"P3V3_STBY_VR"
CDS_LIB"mstr_discrete"
BOM_COST"P3V3_STBY_VR"
PART_NUMBER"A36096-046"
VALUE"1000PF"
LOCATION"C8F2"
TOLERANCE"10%"
PACK_TYPE"0402LF"
VOLTAGE"50V"
MATERIAL"X7R";
"A"
$PN"1"35;
"B"
$PN"2"3;
%"RES"
"2","(6275,3900)","2","mstr_discrete","I117";
;
CDS_SEC"1"
SEC_TYPE"0402"
REUSE_ID"21"
SEC"1"
BOM_COST"P3V3_STBY_VR"
ROOM"PVPP_KLM_VR"
CDS_LIB"mstr_discrete"
CDS_LOCATION"R8F5"
TOLERANCE"1%"
LOCATION"R8F5"
PART_NUMBER"G21796-026"
VALUE"1.00K"
PACK_TYPE"0402"
MATERIAL"CHIP"
WATTAGE"1/16W";
"A"
$PN"1"5;
"B"
$PN"2"35;
%"RT8240"
"1","(7550,2625)","0","mstr_vreg","I125";
;
CDS_SEC"1"
PACK_TYPE"QFN"
SEC_TYPE"QFN"
SEC"1"
CDS_LOCATION"EU8F1"
ROOM"P3V3_STBY_VR"
CDS_LIB"mstr_vreg"
LOCATION"EU8F1"
MATERIAL"IC"
PART_NUMBER"H66262-001";
"GND<0>"
$PN"12"15;
"CS"
$PN"10"37;
"GND<1>"
$PN"13"15;
"RGND"
$PN"7"30;
"VOUT"
$PN"6"29;
"LGATE"
$PN"1"27;
"PHASE"
$PN"2"25;
"UGATE"
$PN"3"28;
"BOOT"
$PN"4"33;
"G0"
$PN"11"15;
"EN"
$PN"8"36;
"PGOOD"
$PN"9"35;
"VCC"
$PN"5"2;
%"RES"
"1","(7600,3425)","0","mstr_discrete","I127";
;
$SEC"1"
CDS_SEC"1"
REUSE_ID"13"
SPOF"TRUE"
BOM_COST"P3V3_STBY_VR"
CDS_LIB"mstr_discrete"
ROOM"P3V3_STBY_VR"
CDS_LOCATION"R8E35"
LOCATION"R8E35"
PART_NUMBER"G21497-005"
PACK_TYPE"0402"
MATERIAL"CHIP"
TOLERANCE"5%"
WATTAGE"1/16W"
VALUE"0.0";
"B"
$PN"2"32;
"A"
$PN"1"33;
%"GND"
"1","(8150,4025)","0","mstr_symbols","I128";
;
SIZE"1B"
HDL_POWER"GND"
ROOM"PVPP_KLM_VR"
BOM_COST"PVPP_KLM_VR"
BODY_TYPE"PLUMBING"
CDS_LIB"mstr_symbols"
VOLTAGE"0";
"A\NAC"4;
%"CAP"
"2","(8300,3425)","2","mstr_discrete","I129";
;
$SEC"1"
CDS_SEC"1"
SPOF"TRUE"
REUSE_ID"27"
BOM_COST"P3V3_STBY_VR"
CDS_LIB"mstr_discrete"
CDS_LOCATION"C8E12"
ROOM"P3V3_STBY_VR"
LOCATION"C8E12"
VALUE"0.1UF"
VOLTAGE"25V"
TOLERANCE"10%"
PACK_TYPE"0603LF"
MATERIAL"X7R"
PART_NUMBER"602433-020";
"A"
$PN"1"25;
"B"
$PN"2"32;
%"P3V3_STBY"
"1","(6275,4150)","0","mstr_symbols","I130";
;
VOLTAGE"+3.3V"
SIZE"1B"
CDS_LIB"mstr_symbols"
BODY_TYPE"PLUMBING"
HDL_POWER"P3V3_STBY";
"G\NAC"5;
%"P12V_STBY"
"1","(6750,4650)","0","mstr_symbols","I131";
;
SIZE"1B"
CDS_LIB"mstr_symbols"
VOLTAGE"12.0V"
BODY_TYPE"PLUMBING"
HDL_POWER"P12V_STBY";
"G\NAC"6;
%"FERRITE"
"1","(6900,4500)","0","mstr_discrete","I132";
;
CDS_SEC"1"
TOLERANCE"1%"
SEC_TYPE"SM"
SEC"1"
ROOM"P3V3_STBY_VR"
CDS_LIB"mstr_discrete"
CDS_LOCATION"FB9E1"
PART_NUMBER"656554-051"
PACK_TYPE"SM"
LOCATION"FB9E1"
MATERIAL"FB"
VALUE"22";
"A"
$PN"1"6;
"B"
$PN"2"24;
%"GND"
"1","(7125,4175)","0","mstr_symbols","I133";
;
SIZE"1B"
HDL_POWER"GND"
VOLTAGE"0"
CDS_LIB"mstr_symbols"
BODY_TYPE"PLUMBING"
ROOM"PVPP_KLM_VR"
BOM_COST"PVPP_KLM_VR";
"A\NAC"41;
%"CAP"
"1","(7125,4325)","0","mstr_discrete","I134";
;
CDS_SEC"1"
$SEC"1"
CDS_LOCATION"C9F1"
BOM_COST"P3V3_STBY_VR"
CDS_LIB"mstr_discrete"
ROOM"P3V3_STBY_VR"
PART_NUMBER"D38464-007"
LOCATION"C9F1"
VALUE"47UF"
TOLERANCE"20%"
PACK_TYPE"1210"
VOLTAGE"16V"
MATERIAL"X6S";
"A"
$PN"1"24;
"B"
$PN"2"41;
%"CAP"
"1","(7475,4325)","0","mstr_discrete","I135";
;
CDS_LOCATION"C8E11"
$SEC"1"
CDS_SEC"1"
BOM_COST"P3V3_STBY_VR"
CDS_LIB"mstr_discrete"
ROOM"P3V3_STBY_VR"
PART_NUMBER"D38464-007"
VALUE"47UF"
LOCATION"C8E11"
TOLERANCE"20%"
PACK_TYPE"1210"
VOLTAGE"16V"
MATERIAL"X6S";
"A"
$PN"1"24;
"B"
$PN"2"40;
%"GND"
"1","(7475,4175)","0","mstr_symbols","I136";
;
HDL_POWER"GND"
VOLTAGE"0"
SIZE"1B"
CDS_LIB"mstr_symbols"
BODY_TYPE"PLUMBING"
ROOM"PVPP_KLM_VR"
BOM_COST"PVPP_KLM_VR";
"A\NAC"40;
%"CAP"
"1","(7825,4325)","0","mstr_discrete","I137";
;
CDS_SEC"1"
$SEC"1"
CDS_LOCATION"C8E10"
BOM_COST"P3V3_STBY_VR"
CDS_LIB"mstr_discrete"
ROOM"P3V3_STBY_VR"
LOCATION"C8E10"
PART_NUMBER"D38464-005"
VALUE"22UF"
TOLERANCE"10%"
PACK_TYPE"1206LF"
VOLTAGE"16V"
MATERIAL"X6S";
"A"
$PN"1"24;
"B"
$PN"2"39;
%"GND"
"1","(7825,4175)","0","mstr_symbols","I138";
;
HDL_POWER"GND"
SIZE"1B"
VOLTAGE"0"
CDS_LIB"mstr_symbols"
BODY_TYPE"PLUMBING"
ROOM"PVPP_KLM_VR"
BOM_COST"PVPP_KLM_VR";
"A\NAC"39;
%"CAP"
"1","(8150,4350)","0","mstr_discrete","I139";
;
REUSE_ID"1"
FIN"VR_1P2"
CDS_SEC"1"
$SEC"1"
CDS_LOCATION"C8E14"
ROOM"P3V3_STBY_VR"
BOM_COST"P3V3_STBY_VR"
CDS_LIB"mstr_discrete"
LOCATION"C8E14"
PART_NUMBER"D97712-011"
VALUE"1.0UF"
TOLERANCE"10%"
PACK_TYPE"0402"
VOLTAGE"16V"
MATERIAL"X6S";
"A"
$PN"1"24;
"B"
$PN"2"4;
%"RES"
"1","(9225,925)","0","mstr_discrete","I140";
;
BOM_COST"P3V3_STBY_VR"
MATERIAL"CHIP"
CDS_LIB"mstr_discrete"
ROOM"P3V3_STBY_VR"
$SEC"1"
CDS_SEC"1"
CDS_LOCATION"R8E38"
PART_NUMBER"G21497-005"
TOLERANCE"5%"
LOCATION"R8E38"
PACK_TYPE"0402"
WATTAGE"1/16W"
VALUE"0.0";
"B"
$PN"2"19;
"A"
$PN"1"30;
%"RES"
"2","(9475,1100)","0","mstr_discrete","I142";
;
CDS_SEC"1"
REUSE_ID"7"
SPOF"TRUE"
$SEC"1"
CDS_LOCATION"R8E34"
CDS_LIB"mstr_discrete"
ROOM"P3V3_STBY_VR"
BOM_COST"P3V3_STBY_VR"
WATTAGE"1/16W"
MATERIAL"CHIP"
VALUE"10.0K"
LOCATION"R8E34"
TOLERANCE"1%"
PART_NUMBER"G21796-016"
PACK_TYPE"0402";
"A"
$PN"1"29;
"B"
$PN"2"19;
%"RES"
"2","(9475,1425)","0","mstr_discrete","I143";
;
SPOF"TRUE"
BOM_COST"P3V3_STBY_VR"
REUSE_ID"9"
CDS_SEC"1"
$SEC"1"
CDS_LOCATION"R8E31"
ROOM"P3V3_STBY_VR"
CDS_LIB"mstr_discrete"
PART_NUMBER"G21796-114"
LOCATION"R8E31"
MATERIAL"CHIP"
WATTAGE"1/16W"
PACK_TYPE"0402"
VALUE"23.2K"
TOLERANCE"1%";
"A"
$PN"1"31;
"B"
$PN"2"29;
%"RES"
"1","(9475,1825)","5","mstr_discrete","I144";
;
CDS_SEC"1"
ROOM"PVPP_KLM_VR"
CDS_LIB"mstr_discrete"
SEC_TYPE"0402"
SPOF"TRUE"
SEC"1"
CDS_LOCATION"R8E25"
PART_NUMBER"G21497-005"
WATTAGE"1/16W"
VALUE"0.0"
LOCATION"R8E25"
TOLERANCE"5%"
MATERIAL"CHIP"
PACK_TYPE"0402";
"B"
$PN"2"31;
"A"
$PN"1"23;
%"GND"
"1","(10175,1625)","0","mstr_symbols","I145";
;
SIZE"1B"
VOLTAGE"0"
CDS_LIB"mstr_symbols"
BODY_TYPE"PLUMBING"
HDL_POWER"GND"
ROOM"PVPP_KLM_VR"
BOM_COST"PVPP_KLM_VR";
"A\NAC"7;
%"RES"
"1","(10475,1725)","0","mstr_discrete","I146";
;
ROOM"P3V3_STBY_VR"
$SEC"1"
CDS_SEC"1"
CDS_LOCATION"R8F11"
CDS_LIB"mstr_discrete"
LOCATION"R8F11"
PART_NUMBER"G21497-005"
TOLERANCE"5%"
MATERIAL"CHIP"
WATTAGE"1/16W"
VALUE"0.0"
PACK_TYPE"0402";
"B"
$PN"2"20;
"A"
$PN"1"7;
%"GND"
"1","(9875,3075)","0","mstr_symbols","I147";
;
CDS_LIB"mstr_symbols"
VOLTAGE"0"
HDL_POWER"GND"
ROOM"PVPP_KLM_VR"
SIZE"1B"
BODY_TYPE"PLUMBING"
BOM_COST"PVPP_KLM_VR";
"A\NAC"8;
%"RES"
"2","(10450,3550)","0","mstr_discrete","I148";
;
BOM_COST"P3V3_STBY_VR"
REUSE_ID"29"
CDS_SEC"1"
$SEC"1"
ROOM"P3V3_STBY_VR"
CDS_LOCATION"R8F3"
CDS_LIB"mstr_discrete"
PART_NUMBER"G21497-016"
VALUE"2.2"
LOCATION"R8F3"
TOLERANCE"5%"
MATERIAL"EMPTY"
PACK_TYPE"0402"
WATTAGE"1/16W";
"A"
$PN"1"26;
"B"
$PN"2"9;
%"GND"
"1","(10450,3350)","0","mstr_symbols","I149";
;
HDL_POWER"GND"
SIZE"1B"
VOLTAGE"0"
CDS_LIB"mstr_symbols"
BODY_TYPE"PLUMBING"
ROOM"PVPP_KLM_VR"
BOM_COST"PVPP_KLM_VR";
"A\NAC"9;
%"GND"
"1","(11025,3625)","0","mstr_symbols","I151";
;
HDL_POWER"GND"
CDS_LIB"mstr_symbols"
VOLTAGE"0"
SIZE"1B"
BODY_TYPE"PLUMBING"
ROOM"PVPP_KLM_VR"
BOM_COST"PVPP_KLM_VR";
"A\NAC"10;
%"RES"
"2","(11025,3875)","0","mstr_discrete","I152";
;
REUSE_ID"34"
CDS_SEC"1"
$SEC"1"
BOM_COST"P3V3_STBY_VR"
CDS_LOCATION"R2T4"
ROOM"P3V3_STBY_VR"
CDS_LIB"mstr_discrete"
PART_NUMBER"G85996-004"
TOLERANCE"0.1%"
VALUE"1.0K"
LOCATION"R2T4"
WATTAGE"1/16W"
MATERIAL"CHIP"
PACK_TYPE"0402";
"A"
$PN"1"23;
"B"
$PN"2"10;
%"GND"
"1","(11350,3650)","0","mstr_symbols","I153";
;
SIZE"1B"
HDL_POWER"GND"
BODY_TYPE"PLUMBING"
CDS_LIB"mstr_symbols"
VOLTAGE"0"
ROOM"PVPP_KLM_VR"
BOM_COST"PVPP_KLM_VR";
"A\NAC"11;
%"CAPP"
"1","(11350,3875)","0","mstr_discrete","I154";
;
REUSE_ID"28"
CDS_SEC"1"
$SEC"1"
CDS_LOCATION"C8F14"
BOM_COST"P3V3_STBY_VR"
CDS_LIB"mstr_discrete"
ROOM"P3V3_STBY_VR"
LOCATION"C8F14"
PART_NUMBER"724613-091"
VALUE"470UF"
MATERIAL"POSCAP"
TOLERANCE"20%"
VOLTAGE"6.3V"
PACK_TYPE"3018";
"B"
$PN"2"11;
"A"
$PN"1"23;
%"CAPP"
"1","(11675,3875)","0","mstr_discrete","I155";
;
REUSE_ID"28"
CDS_SEC"1"
$SEC"1"
CDS_LOCATION"C8F8"
BOM_COST"P3V3_STBY_VR"
CDS_LIB"mstr_discrete"
ROOM"P3V3_STBY_VR"
LOCATION"C8F8"
PART_NUMBER"724613-091"
VALUE"470UF"
TOLERANCE"20%"
PACK_TYPE"3018"
VOLTAGE"6.3V"
MATERIAL"POSCAP";
"B"
$PN"2"12;
"A"
$PN"1"23;
%"GND"
"1","(11675,3650)","0","mstr_symbols","I156";
;
HDL_POWER"GND"
VOLTAGE"0"
SIZE"1B"
CDS_LIB"mstr_symbols"
BODY_TYPE"PLUMBING"
ROOM"PVPP_KLM_VR"
BOM_COST"PVPP_KLM_VR";
"A\NAC"12;
%"GND"
"1","(11950,3600)","0","mstr_symbols","I157";
;
HDL_POWER"GND"
VOLTAGE"0"
CDS_LIB"mstr_symbols"
SIZE"1B"
BODY_TYPE"PLUMBING"
ROOM"PVPP_KLM_VR"
BOM_COST"PVPP_KLM_VR";
"A\NAC"13;
%"CAP"
"1","(11950,3875)","0","mstr_discrete","I158";
;
REUSE_ID"33"
CDS_SEC"1"
$SEC"1"
CDS_LOCATION"C2T7"
CDS_LIB"mstr_discrete"
BOM_COST"P3V3_STBY_VR"
ROOM"P3V3_STBY_VR"
PART_NUMBER"C95333-008"
LOCATION"C2T7"
VALUE"22UF"
TOLERANCE"20%"
PACK_TYPE"0805"
VOLTAGE"6.3V"
MATERIAL"X6S";
"A"
$PN"1"23;
"B"
$PN"2"13;
%"GND"
"1","(12175,3600)","0","mstr_symbols","I159";
;
HDL_POWER"GND"
CDS_LIB"mstr_symbols"
VOLTAGE"0"
SIZE"1B"
BODY_TYPE"PLUMBING"
ROOM"PVPP_KLM_VR"
BOM_COST"PVPP_KLM_VR";
"A\NAC"14;
%"CAP"
"1","(12175,3850)","0","mstr_discrete","I160";
;
CDS_SEC"1"
REUSE_ID"33"
$SEC"1"
CDS_LOCATION"C2T6"
BOM_COST"P3V3_STBY_VR"
CDS_LIB"mstr_discrete"
ROOM"P3V3_STBY_VR"
LOCATION"C2T6"
PART_NUMBER"C95333-008"
VALUE"22UF"
TOLERANCE"20%"
PACK_TYPE"0805"
VOLTAGE"6.3V"
MATERIAL"X6S";
"A"
$PN"1"23;
"B"
$PN"2"14;
%"CAP"
"1","(10450,3900)","0","mstr_discrete","I163";
;
REUSE_ID"26"
CDS_SEC"1"
$SEC"1"
BOM_COST"P3V3_STBY_VR"
CDS_LOCATION"C8F3"
ROOM"P3V3_STBY_VR"
CDS_LIB"mstr_discrete"
MATERIAL"EMPTY"
PART_NUMBER"A36096-091"
LOCATION"C8F3"
VALUE"3300PF"
TOLERANCE"10%"
VOLTAGE"50V"
PACK_TYPE"0402LF";
"A"
$PN"1"25;
"B"
$PN"2"26;
%"AGND_SCSI"
"1","(6975,2100)","0","mstr_symbols","I164";
;
CDS_LIB"mstr_symbols"
BODY_TYPE"PLUMBING"
VOLTAGE"0V"
HDL_POWER"AGND_P3V3_STBY";
"A"15;
%"AGND_SCSI"
"1","(6425,1550)","0","mstr_symbols","I165";
;
CDS_LIB"mstr_symbols"
VOLTAGE"0V"
BODY_TYPE"PLUMBING"
HDL_POWER"AGND_P3V3_STBY";
"A"16;
%"AGND_SCSI"
"1","(6175,2175)","0","mstr_symbols","I166";
;
CDS_LIB"mstr_symbols"
VOLTAGE"0V"
BODY_TYPE"PLUMBING"
HDL_POWER"AGND_P3V3_STBY";
"A"17;
%"AGND_SCSI"
"1","(5600,2925)","0","mstr_symbols","I167";
;
BODY_TYPE"PLUMBING"
CDS_LIB"mstr_symbols"
VOLTAGE"0V"
HDL_POWER"AGND_P3V3_STBY";
"A"18;
%"AGND_SCSI"
"1","(9475,800)","0","mstr_symbols","I168";
;
CDS_LIB"mstr_symbols"
VOLTAGE"0V"
BODY_TYPE"PLUMBING"
HDL_POWER"AGND_P3V3_STBY";
"A"19;
%"AGND_SCSI"
"1","(10725,1625)","0","mstr_symbols","I169";
;
CDS_LIB"mstr_symbols"
BODY_TYPE"PLUMBING"
VOLTAGE"0V"
HDL_POWER"AGND_P3V3_STBY";
"A"20;
%"CSD87384M"
"1","(9475,3425)","0","mstr_discrete","I170";
;
CDS_SEC"1"
ROOM"P3V3_STBY_VR"
CDS_LOCATION"EU8E1"
SEC"1"
SEC_TYPE"SM"
PACK_TYPE"SM"
CDS_LIB"mstr_discrete"
LOCATION"EU8E1"
MATERIAL"IC"
PART_NUMBER"H66258-001";
"BG"
$PN"4"27;
"TG"
$PN"1"28;
"VIN"
$PN"2"24;
"VSW"
$PN"5"25;
"PGND"
$PN"3"8;
%"RES"
"1","(7175,3825)","0","mstr_discrete","I171";
;
CDS_SEC"1"
CDS_LIB"mstr_discrete"
SEC_TYPE"0402"
SEC"1"
CDS_LOCATION"R8F10"
ROOM"P3V3_STBY_VR"
PACK_TYPE"0402"
MATERIAL"CHIP"
TOLERANCE"1.0%"
LOCATION"R8F10"
PART_NUMBER"G21796-250"
VALUE"22.1"
WATTAGE"1/16W";
"B"
$PN"2"34;
"A"
$PN"1"35;
%"INDUCTOR"
"1","(10800,4050)","0","mstr_discrete","I173";
;
CDS_SEC"1"
$SEC"1"
CDS_LOCATION"L8F1"
CDS_LIB"mstr_discrete"
LOCATION"L8F1"
PART_NUMBER"E98679-006"
PACK_TYPE"SM"
MATERIAL"IND"
VALUE"1.00UH";
"INA\NAC"
$PN"1"25;
"INB\NAC"
$PN"2"23;
%"CAP"
"1","(12425,3850)","0","mstr_discrete","I174";
;
$SEC"1"
CDS_SEC"1"
REUSE_ID"33"
CDS_LOCATION"C2T9"
BOM_COST"P3V3_STBY_VR"
CDS_LIB"mstr_discrete"
ROOM"P3V3_STBY_VR"
LOCATION"C2T9"
PART_NUMBER"C95333-008"
VALUE"22UF"
TOLERANCE"20%"
PACK_TYPE"0805"
VOLTAGE"6.3V"
MATERIAL"X6S";
"A"
$PN"1"23;
"B"
$PN"2"21;
%"GND"
"1","(12425,3575)","0","mstr_symbols","I175";
;
HDL_POWER"GND"
VOLTAGE"0"
CDS_LIB"mstr_symbols"
SIZE"1B"
BODY_TYPE"PLUMBING"
ROOM"PVPP_KLM_VR"
BOM_COST"PVPP_KLM_VR";
"A\NAC"21;
%"RES"
"1","(6525,2725)","0","mstr_discrete","I176";
;
ROOM"PVCCIN_CPU0_VR"
$SEC"1"
CDS_SEC"1"
CDS_LIB"mstr_discrete"
CDS_LOCATION"R8F2"
PART_NUMBER"G21497-005"
PACK_TYPE"0402"
LOCATION"R8F2"
TOLERANCE"5%"
MATERIAL"CHIP"
VALUE"0.0"
WATTAGE"1/16W";
"B"
$PN"2"36;
"A"
$PN"1"38;
%"RES"
"2","(6950,3250)","0","mstr_discrete","I177";
;
BOM_COST"SM_CONTROLLER"
CDS_SEC"1"
$SEC"1"
ROOM"BMC"
CDS_LOCATION"R8E40"
CDS_LIB"mstr_discrete"
PART_NUMBER"G21796-010"
VALUE"100.0K"
LOCATION"R8E40"
MATERIAL"EMPTY"
TOLERANCE"1%"
PACK_TYPE"0402"
WATTAGE"1/16W";
"A"
$PN"1"22;
"B"
$PN"2"36;
%"P3V3_STBY"
"1","(6950,3500)","0","mstr_symbols","I178";
;
VOLTAGE"+3.3V"
SIZE"1B"
CDS_LIB"mstr_symbols"
BODY_TYPE"PLUMBING"
HDL_POWER"P3V3_STBY";
"G\NAC"22;
%"P3V3_STBY"
"1","(12575,4225)","0","mstr_symbols","I85";
;
VOLTAGE"+3.3V"
SIZE"1B"
CDS_LIB"mstr_symbols"
BODY_TYPE"PLUMBING"
HDL_POWER"P3V3_STBY";
"G\NAC"23;
END.
